(kicad_pcb
	(version 20260206)
	(generator "pcbnew")
	(generator_version "10.0")
	(general
		(thickness 1.6)
		(legacy_teardrops no)
	)
	(paper "A4")
	(title_block
		(title "v1-chassis-manager — T6M_CM_d_v01_1031_1645.brd")
		(comment 1 "Open CloudServer (Microsoft) / footprints 1095-1101 of 2512")
	)
	(layers
		(0 "F.Cu" signal "TOP")
		(4 "In1.Cu" signal "GND1")
		(6 "In2.Cu" signal "IN1")
		(8 "In3.Cu" signal "VCC1")
		(10 "In4.Cu" signal "VCC2")
		(12 "In5.Cu" signal "GND2")
		(14 "In6.Cu" signal "IN2")
		(16 "In7.Cu" signal "IN3")
		(18 "In8.Cu" signal "GND3")
		(2 "B.Cu" signal "BOTTOM")
		(9 "F.Adhes" user "F.Adhesive")
		(11 "B.Adhes" user "B.Adhesive")
		(13 "F.Paste" user "Package Geometry/Pastemask Top")
		(15 "B.Paste" user "Package Geometry/Pastemask Bottom")
		(5 "F.SilkS" user "Ref Des/Silkscreen Top")
		(7 "B.SilkS" user "Ref Des/Silkscreen Bottom")
		(1 "F.Mask" user "Board Geometry/Soldermask Top")
		(3 "B.Mask" user "Board Geometry/Soldermask Bottom")
		(17 "Dwgs.User" user "User.Drawings")
		(19 "Cmts.User" user "User.Comments")
		(21 "Eco1.User" user "User.Eco1")
		(23 "Eco2.User" user "User.Eco2")
		(25 "Edge.Cuts" user "Board Geometry/Outline")
		(27 "Margin" user)
		(31 "F.CrtYd" user "Package Geometry/Place Bound Top")
		(29 "B.CrtYd" user "Package Geometry/Place Bound Bottom")
		(35 "F.Fab" user "Ref Des/Assembly Top")
		(33 "B.Fab" user "Ref Des/Assembly Bottom")
	)
	(footprint ""
		(layer "F.Cu")
		(at -11.397488 -191.641222 -90)
		(property "Reference" "J25"
			(at 2.96672 1.84277 90)
			(unlocked yes)
			(layer "F.SilkS")
			(effects
				(font
					(size 0.7874 0.5842)
					(thickness 0.1524)
				)
				(justify left)
			)
		)
		(property "Value" ""
			(at 0 0 270)
			(layer "F.Fab")
			(effects
				(font
					(size 1.27 1.27)
				)
			)
		)
		(duplicate_pad_numbers_are_jumpers no)
		(fp_circle
			(center 0 0)
			(end 0 -0.635)
			(stroke
				(width 0.05)
				(type default)
			)
			(fill no)
			(layer "Edge.Cuts")
		)
		(fp_circle
			(center 4.064 0)
			(end 4.064 -0.635)
			(stroke
				(width 0.05)
				(type default)
			)
			(fill no)
			(layer "Edge.Cuts")
		)
		(fp_circle
			(center 0 -4.572)
			(end 0 -5.207)
			(stroke
				(width 0.05)
				(type default)
			)
			(fill no)
			(layer "Edge.Cuts")
		)
		(fp_circle
			(center 4.064 -4.572)
			(end 4.064 -5.207)
			(stroke
				(width 0.05)
				(type default)
			)
			(fill no)
			(layer "Edge.Cuts")
		)
		(fp_rect
			(start -1.27 1.27)
			(end 5.334 -5.842)
			(stroke
				(width 0)
				(type default)
			)
			(fill no)
			(layer "F.CrtYd")
		)
		(pad "" np_thru_hole circle
			(at 0 -4.572 270)
			(size 0.254 0.254)
			(drill 1.27)
			(layers "*.Cu" "*.Mask")
			(clearance 0.889)
			(thermal_gap 0.889)
		)
		(pad "" np_thru_hole circle
			(at 0 0 270)
			(size 0.254 0.254)
			(drill 1.27)
			(layers "*.Cu" "*.Mask")
			(clearance 0.889)
			(thermal_gap 0.889)
		)
		(pad "" np_thru_hole circle
			(at 4.064 -4.572 270)
			(size 0.254 0.254)
			(drill 1.27)
			(layers "*.Cu" "*.Mask")
			(clearance 0.889)
			(thermal_gap 0.889)
		)
		(pad "" np_thru_hole circle
			(at 4.064 0 270)
			(size 0.254 0.254)
			(drill 1.27)
			(layers "*.Cu" "*.Mask")
			(clearance 0.889)
			(thermal_gap 0.889)
		)
		(pad "1" thru_hole custom
			(at 1.397 -2.286)
			(size 0.266741 0.266741)
			(drill 0.254)
			(layers "*.Cu" "*.Mask")
			(remove_unused_layers no)
			(net "GND")
			(options
				(clearance outline)
				(anchor circle)
			)
			(primitives
				(gr_poly
					(pts
						(xy -0.979932 0.5334)
						(arc
							(start -0.979932 -0.078994)
							(mid -0.925932 -0.48038)
							(end -0.527812 -0.4064)
						)
						(arc
							(start -0.234188 -0.4064)
							(mid 0 -0.53341)
							(end 0.234188 -0.4064)
						)
						(arc
							(start 0.527812 -0.4064)
							(mid 0.925878 -0.480305)
							(end 0.979932 -0.078994)
						)
						(xy 0.979932 0.5334) (xy 0.548132 0.5334) (xy 0.548132 0.1016) (xy -0.548132 0.1016) (xy -0.548132 0.5334)
					)
					(width 0)
					(fill yes)
				)
			)
			(padstack
				(mode front_inner_back)
				(layer "Inner"
					(shape custom)
					(size 0.139735 0.139735)
					(options
						(anchor circle)
					)
					(primitives
						(gr_poly
							(pts
								(arc
									(start 0.26035 0.1016)
									(mid 0 0.279472)
									(end -0.26035 0.1016)
								)
								(arc
									(start -0.50165 0.1016)
									(mid -1.041472 0)
									(end -0.50165 -0.1016)
								)
								(arc
									(start -0.26035 -0.1016)
									(mid 0 -0.279472)
									(end 0.26035 -0.1016)
								)
								(arc
									(start 0.50165 -0.1016)
									(mid 1.041472 0)
									(end 0.50165 0.1016)
								)
							)
							(width 0)
							(fill yes)
						)
					)
				)
				(layer "B.Cu"
					(shape custom)
					(size 0.139735 0.139735)
					(options
						(anchor circle)
					)
					(primitives
						(gr_poly
							(pts
								(arc
									(start 0.26035 0.1016)
									(mid 0 0.279472)
									(end -0.26035 0.1016)
								)
								(arc
									(start -0.50165 0.1016)
									(mid -1.041472 0)
									(end -0.50165 -0.1016)
								)
								(arc
									(start -0.26035 -0.1016)
									(mid 0 -0.279472)
									(end 0.26035 -0.1016)
								)
								(arc
									(start 0.50165 -0.1016)
									(mid 1.041472 0)
									(end 0.50165 0.1016)
								)
							)
							(width 0)
							(fill yes)
						)
					)
				)
			)
		)
		(pad "2" smd rect
			(at 2.032 -2.060956 270)
			(size 0.3048 0.2032)
			(layers "F.Cu" "F.Mask" "F.Paste")
			(net "IN3_85OHM")
		)
		(pad "3" smd rect
			(at 2.032 -2.511044 270)
			(size 0.3048 0.2032)
			(layers "F.Cu" "F.Mask" "F.Paste")
			(net "IN3_85OHM")
		)
		(zone
			(layers "F.Cu" "B.Cu" "In1.Cu" "In2.Cu" "In3.Cu" "In4.Cu" "In5.Cu" "In6.Cu"
				"In7.Cu" "In8.Cu"
			)
			(hatch none 0.5)
			(connect_pads
				(clearance 0)
			)
			(min_thickness 0.25)
			(keepout
				(tracks not_allowed)
				(vias allowed)
				(pads allowed)
				(copperpour not_allowed)
				(footprints allowed)
			)
			(placement
				(enabled no)
				(sheetname "")
			)
			(fill
				(thermal_gap 0.5)
				(thermal_bridge_width 0.5)
				(island_removal_mode 0)
			)
			(polygon
				(pts
					(arc
						(start -11.397488 -190.752222)
						(mid -11.397488 -192.530222)
						(end -11.397488 -190.752222)
					)
				)
			)
		)
		(zone
			(layers "F.Cu" "B.Cu" "In1.Cu" "In2.Cu" "In3.Cu" "In4.Cu" "In5.Cu" "In6.Cu"
				"In7.Cu" "In8.Cu"
			)
			(hatch none 0.5)
			(connect_pads
				(clearance 0)
			)
			(min_thickness 0.25)
			(keepout
				(tracks not_allowed)
				(vias allowed)
				(pads allowed)
				(copperpour not_allowed)
				(footprints allowed)
			)
			(placement
				(enabled no)
				(sheetname "")
			)
			(fill
				(thermal_gap 0.5)
				(thermal_bridge_width 0.5)
				(island_removal_mode 0)
			)
			(polygon
				(pts
					(arc
						(start -11.397488 -186.688222)
						(mid -11.397488 -188.466222)
						(end -11.397488 -186.688222)
					)
				)
			)
		)
		(zone
			(layers "F.Cu" "B.Cu" "In1.Cu" "In2.Cu" "In3.Cu" "In4.Cu" "In5.Cu" "In6.Cu"
				"In7.Cu" "In8.Cu"
			)
			(hatch none 0.5)
			(connect_pads
				(clearance 0)
			)
			(min_thickness 0.25)
			(keepout
				(tracks not_allowed)
				(vias allowed)
				(pads allowed)
				(copperpour not_allowed)
				(footprints allowed)
			)
			(placement
				(enabled no)
				(sheetname "")
			)
			(fill
				(thermal_gap 0.5)
				(thermal_bridge_width 0.5)
				(island_removal_mode 0)
			)
			(polygon
				(pts
					(arc
						(start -6.825488 -190.752222)
						(mid -6.825488 -192.530222)
						(end -6.825488 -190.752222)
					)
				)
			)
		)
		(zone
			(layers "F.Cu" "B.Cu" "In1.Cu" "In2.Cu" "In3.Cu" "In4.Cu" "In5.Cu" "In6.Cu"
				"In7.Cu" "In8.Cu"
			)
			(hatch none 0.5)
			(connect_pads
				(clearance 0)
			)
			(min_thickness 0.25)
			(keepout
				(tracks not_allowed)
				(vias allowed)
				(pads allowed)
				(copperpour not_allowed)
				(footprints allowed)
			)
			(placement
				(enabled no)
				(sheetname "")
			)
			(fill
				(thermal_gap 0.5)
				(thermal_bridge_width 0.5)
				(island_removal_mode 0)
			)
			(polygon
				(pts
					(arc
						(start -6.825488 -186.688222)
						(mid -6.825488 -188.466222)
						(end -6.825488 -186.688222)
					)
				)
			)
		)
	)
	(footprint ""
		(layer "F.Cu")
		(at 44.885356 -176.28616 180)
		(property "Reference" "R1006"
			(at 1.63957 -132.978144 0)
			(unlocked yes)
			(layer "F.SilkS")
			(effects
				(font
					(size 0.7874 0.5842)
					(thickness 0.1524)
				)
				(justify left)
			)
		)
		(property "Value" ""
			(at 0 0 180)
			(layer "F.Fab")
			(effects
				(font
					(size 1.27 1.27)
				)
			)
		)
		(duplicate_pad_numbers_are_jumpers no)
		(fp_line
			(start 0.7874 0.4064)
			(end -0.7874 0.4064)
			(stroke
				(width 0.1524)
				(type default)
			)
			(layer "F.SilkS")
		)
		(fp_line
			(start 0.7874 -0.4064)
			(end 0.7874 0.4064)
			(stroke
				(width 0.1524)
				(type default)
			)
			(layer "F.SilkS")
		)
		(fp_line
			(start -0.7874 0.4064)
			(end -0.7874 -0.4064)
			(stroke
				(width 0.1524)
				(type default)
			)
			(layer "F.SilkS")
		)
		(fp_line
			(start -0.7874 -0.4064)
			(end 0.7874 -0.4064)
			(stroke
				(width 0.1524)
				(type default)
			)
			(layer "F.SilkS")
		)
		(fp_poly
			(pts
				(xy -0.508 0.2794) (xy -0.508 0.2286) (xy -0.635 0.2286) (xy -0.635 -0.254) (xy -0.5334 -0.254)
				(xy -0.5334 -0.2794) (xy 0.5334 -0.2794) (xy 0.5334 -0.254) (xy 0.635 -0.254) (xy 0.635 0.254) (xy 0.5334 0.254)
				(xy 0.5334 0.2794)
			)
			(stroke
				(width 0)
				(type default)
			)
			(fill no)
			(layer "F.CrtYd")
		)
		(pad "1" smd rect
			(at 0.40005 0 180)
			(size 0.4572 0.508)
			(layers "F.Cu" "F.Mask" "F.Paste")
			(net "P12V_AUX_EN")
		)
		(pad "2" smd rect
			(at -0.40005 0 180)
			(size 0.4572 0.508)
			(layers "F.Cu" "F.Mask" "F.Paste")
			(net "P12V_PDB")
		)
	)
	(footprint ""
		(layer "F.Cu")
		(at 113.420144 -140.193522 -90)
		(property "Reference" "PR71"
			(at -4.108958 -3.597402 90)
			(unlocked yes)
			(layer "F.SilkS")
			(effects
				(font
					(size 0.635 0.4064)
					(thickness 0.1524)
				)
				(justify left)
			)
		)
		(property "Value" ""
			(at 0 0 270)
			(layer "F.Fab")
			(effects
				(font
					(size 1.27 1.27)
				)
			)
		)
		(duplicate_pad_numbers_are_jumpers no)
		(fp_line
			(start -0.7874 0.4064)
			(end -0.7874 -0.4064)
			(stroke
				(width 0.1524)
				(type default)
			)
			(layer "F.SilkS")
		)
		(fp_line
			(start 0.7874 0.4064)
			(end -0.7874 0.4064)
			(stroke
				(width 0.1524)
				(type default)
			)
			(layer "F.SilkS")
		)
		(fp_line
			(start -0.7874 -0.4064)
			(end 0.7874 -0.4064)
			(stroke
				(width 0.1524)
				(type default)
			)
			(layer "F.SilkS")
		)
		(fp_line
			(start 0.7874 -0.4064)
			(end 0.7874 0.4064)
			(stroke
				(width 0.1524)
				(type default)
			)
			(layer "F.SilkS")
		)
		(fp_poly
			(pts
				(xy -0.508 0.2794) (xy -0.508 0.2286) (xy -0.635 0.2286) (xy -0.635 -0.254) (xy -0.5334 -0.254)
				(xy -0.5334 -0.2794) (xy 0.5334 -0.2794) (xy 0.5334 -0.254) (xy 0.635 -0.254) (xy 0.635 0.254) (xy 0.5334 0.254)
				(xy 0.5334 0.2794)
			)
			(stroke
				(width 0)
				(type default)
			)
			(fill no)
			(layer "F.CrtYd")
		)
		(pad "1" smd rect
			(at 0.40005 0 270)
			(size 0.4572 0.508)
			(layers "F.Cu" "F.Mask" "F.Paste")
			(net "VSENSE_VSS_CPU_NODE1")
		)
		(pad "2" smd rect
			(at -0.40005 0 270)
			(size 0.4572 0.508)
			(layers "F.Cu" "F.Mask" "F.Paste")
			(net "GND")
		)
	)
	(footprint ""
		(layer "F.Cu")
		(at 27.932888 -130.589782 90)
		(property "Reference" "R1094"
			(at -0.722122 -1.999742 90)
			(unlocked yes)
			(layer "F.SilkS")
			(effects
				(font
					(size 0.7874 0.5842)
					(thickness 0.1524)
				)
				(justify left)
			)
		)
		(property "Value" ""
			(at 0 0 90)
			(layer "F.Fab")
			(effects
				(font
					(size 1.27 1.27)
				)
			)
		)
		(duplicate_pad_numbers_are_jumpers no)
		(fp_line
			(start 0.7874 -0.4064)
			(end 0.7874 0.4064)
			(stroke
				(width 0.1524)
				(type default)
			)
			(layer "F.SilkS")
		)
		(fp_line
			(start -0.7874 -0.4064)
			(end 0.7874 -0.4064)
			(stroke
				(width 0.1524)
				(type default)
			)
			(layer "F.SilkS")
		)
		(fp_line
			(start 0.7874 0.4064)
			(end -0.7874 0.4064)
			(stroke
				(width 0.1524)
				(type default)
			)
			(layer "F.SilkS")
		)
		(fp_line
			(start -0.7874 0.4064)
			(end -0.7874 -0.4064)
			(stroke
				(width 0.1524)
				(type default)
			)
			(layer "F.SilkS")
		)
		(fp_poly
			(pts
				(xy -0.508 0.2794) (xy -0.508 0.2286) (xy -0.635 0.2286) (xy -0.635 -0.254) (xy -0.5334 -0.254)
				(xy -0.5334 -0.2794) (xy 0.5334 -0.2794) (xy 0.5334 -0.254) (xy 0.635 -0.254) (xy 0.635 0.254) (xy 0.5334 0.254)
				(xy 0.5334 0.2794)
			)
			(stroke
				(width 0)
				(type default)
			)
			(fill no)
			(layer "F.CrtYd")
		)
		(pad "1" smd rect
			(at 0.40005 0 90)
			(size 0.4572 0.508)
			(layers "F.Cu" "F.Mask" "F.Paste")
			(net "P3V3_STB_NODE1")
		)
		(pad "2" smd rect
			(at -0.40005 0 90)
			(size 0.4572 0.508)
			(layers "F.Cu" "F.Mask" "F.Paste")
			(net "PWRGD_NODE1_P1V538_BMC_PG")
		)
	)
	(footprint ""
		(layer "F.Cu")
		(at 134.239 -51.435 -90)
		(property "Reference" "R1159"
			(at -16.3576 -30.68447 90)
			(unlocked yes)
			(layer "F.SilkS")
			(effects
				(font
					(size 0.7874 0.5842)
					(thickness 0.1524)
				)
				(justify left)
			)
		)
		(property "Value" ""
			(at 0 0 270)
			(layer "F.Fab")
			(effects
				(font
					(size 1.27 1.27)
				)
			)
		)
		(duplicate_pad_numbers_are_jumpers no)
		(fp_line
			(start -0.7874 0.4064)
			(end -0.7874 -0.4064)
			(stroke
				(width 0.1524)
				(type default)
			)
			(layer "F.SilkS")
		)
		(fp_line
			(start 0.7874 0.4064)
			(end -0.7874 0.4064)
			(stroke
				(width 0.1524)
				(type default)
			)
			(layer "F.SilkS")
		)
		(fp_line
			(start -0.7874 -0.4064)
			(end 0.7874 -0.4064)
			(stroke
				(width 0.1524)
				(type default)
			)
			(layer "F.SilkS")
		)
		(fp_line
			(start 0.7874 -0.4064)
			(end 0.7874 0.4064)
			(stroke
				(width 0.1524)
				(type default)
			)
			(layer "F.SilkS")
		)
		(fp_poly
			(pts
				(xy -0.508 0.2794) (xy -0.508 0.2286) (xy -0.635 0.2286) (xy -0.635 -0.254) (xy -0.5334 -0.254)
				(xy -0.5334 -0.2794) (xy 0.5334 -0.2794) (xy 0.5334 -0.254) (xy 0.635 -0.254) (xy 0.635 0.254) (xy 0.5334 0.254)
				(xy 0.5334 0.2794)
			)
			(stroke
				(width 0)
				(type default)
			)
			(fill no)
			(layer "F.CrtYd")
		)
		(pad "1" smd rect
			(at 0.40005 0 270)
			(size 0.4572 0.508)
			(layers "F.Cu" "F.Mask" "F.Paste")
			(net "UART_TX_P3_R")
		)
		(pad "2" smd rect
			(at -0.40005 0 270)
			(size 0.4572 0.508)
			(layers "F.Cu" "F.Mask" "F.Paste")
			(net "UART_TX_P3")
		)
	)
	(footprint ""
		(layer "F.Cu")
		(at 117.07876 -179.363624 -90)
		(property "Reference" "D23"
			(at -3.125724 -6.621272 90)
			(unlocked yes)
			(layer "F.SilkS")
			(effects
				(font
					(size 0.635 0.4064)
					(thickness 0.1524)
				)
				(justify left)
			)
		)
		(property "Value" ""
			(at 0 0 270)
			(layer "F.Fab")
			(effects
				(font
					(size 1.27 1.27)
				)
			)
		)
		(duplicate_pad_numbers_are_jumpers no)
		(fp_line
			(start -1.3208 0.5588)
			(end -1.3208 -0.5588)
			(stroke
				(width 0.1524)
				(type default)
			)
			(layer "F.SilkS")
		)
		(fp_line
			(start 1.3208 0.5588)
			(end -1.3208 0.5588)
			(stroke
				(width 0.1524)
				(type default)
			)
			(layer "F.SilkS")
		)
		(fp_line
			(start 1.6256 0.5588)
			(end 1.6256 -0.5588)
			(stroke
				(width 0.1524)
				(type default)
			)
			(layer "F.SilkS")
		)
		(fp_line
			(start 1.778 0.5588)
			(end 1.3208 0.5588)
			(stroke
				(width 0.1524)
				(type default)
			)
			(layer "F.SilkS")
		)
		(fp_line
			(start -1.3208 -0.5588)
			(end 1.3208 -0.5588)
			(stroke
				(width 0.1524)
				(type default)
			)
			(layer "F.SilkS")
		)
		(fp_line
			(start 1.3208 -0.5588)
			(end 1.3208 0.5588)
			(stroke
				(width 0.1524)
				(type default)
			)
			(layer "F.SilkS")
		)
		(fp_line
			(start 1.4732 -0.5588)
			(end 1.4732 0.5588)
			(stroke
				(width 0.1524)
				(type default)
			)
			(layer "F.SilkS")
		)
		(fp_line
			(start 1.778 -0.5588)
			(end 1.778 0.5588)
			(stroke
				(width 0.1524)
				(type default)
			)
			(layer "F.SilkS")
		)
		(fp_line
			(start 1.778 -0.5588)
			(end 1.3208 -0.5588)
			(stroke
				(width 0.1524)
				(type default)
			)
			(layer "F.SilkS")
		)
		(fp_rect
			(start -1.1684 0.508)
			(end 1.1684 -0.508)
			(stroke
				(width 0)
				(type default)
			)
			(fill no)
			(layer "F.CrtYd")
		)
		(pad "A" smd rect
			(at -0.750062 0 270)
			(size 0.8128 0.8128)
			(layers "F.Cu" "F.Mask" "F.Paste")
			(net "UART_SW_S3_N")
		)
		(pad "C" smd rect
			(at 0.750062 0 270)
			(size 0.8128 0.8128)
			(layers "F.Cu" "F.Mask" "F.Paste")
			(net "N31341803")
		)
	)
	(footprint ""
		(layer "F.Cu")
		(at 35.509962 -3.851148 -90)
		(property "Reference" "Q43"
			(at -0.5461 3.838702 0)
			(unlocked yes)
			(layer "F.SilkS")
			(effects
				(font
					(size 0.7874 0.5842)
					(thickness 0.1524)
				)
			)
		)
		(property "Value" ""
			(at 0 0 270)
			(layer "F.Fab")
			(effects
				(font
					(size 1.27 1.27)
				)
			)
		)
		(duplicate_pad_numbers_are_jumpers no)
		(fp_line
			(start -1.651 1.905)
			(end -1.651 -1.905)
			(stroke
				(width 0.1524)
				(type default)
			)
			(layer "F.SilkS")
		)
		(fp_line
			(start 1.651 1.905)
			(end -1.651 1.905)
			(stroke
				(width 0.1524)
				(type default)
			)
			(layer "F.SilkS")
		)
		(fp_line
			(start -1.651 -1.905)
			(end 1.651 -1.905)
			(stroke
				(width 0.1524)
				(type default)
			)
			(layer "F.SilkS")
		)
		(fp_line
			(start 1.651 -1.905)
			(end 1.651 1.905)
			(stroke
				(width 0.1524)
				(type default)
			)
			(layer "F.SilkS")
		)
		(fp_poly
			(pts
				(xy -1.524 0.7112) (xy -1.524 1.7526) (xy -0.508 1.7526) (xy -0.508 0.6985) (xy 0.508 0.6985) (xy 0.508 1.7526)
				(xy 1.524 1.7526) (xy 1.524 0.6985) (xy 1.524 -0.6985) (xy 0.508 -0.6985) (xy 0.508 -1.7526) (xy -0.508 -1.7526)
				(xy -0.508 -0.6985) (xy -1.524 -0.6985) (xy -1.524 0.6985)
			)
			(stroke
				(width 0)
				(type default)
			)
			(fill no)
			(layer "F.CrtYd")
		)
		(fp_text user "2"
			(at 2.051558 1.254506 270)
			(unlocked yes)
			(layer "F.SilkS")
			(effects
				(font
					(size 0.635 0.4064)
					(thickness 0.1524)
				)
			)
		)
		(fp_text user "1"
			(at -1.98374 1.088644 270)
			(unlocked yes)
			(layer "F.SilkS")
			(effects
				(font
					(size 0.635 0.4064)
					(thickness 0.1524)
				)
			)
		)
		(fp_text user "3"
			(at 2.051558 -0.846074 270)
			(unlocked yes)
			(layer "F.SilkS")
			(effects
				(font
					(size 0.635 0.4064)
					(thickness 0.1524)
				)
			)
		)
		(pad "1" smd rect
			(at -1.016 1.1176 270)
			(size 1.016 1.27)
			(layers "F.Cu" "F.Mask" "F.Paste")
			(net "VR_NODE1_VDDR_1V5_CNTL")
		)
		(pad "2" smd rect
			(at 1.016 1.1176 270)
			(size 1.016 1.27)
			(layers "F.Cu" "F.Mask" "F.Paste")
			(net "GND")
		)
		(pad "3" smd rect
			(at 0 -1.1176 270)
			(size 1.016 1.27)
			(layers "F.Cu" "F.Mask" "F.Paste")
			(net "PV_VDDR_NODE1_VID0")
		)
	)
)
